FILE_TYPE = MACRO_DRAWING;
SET COLOR_WIRE YELLOW;
SET COLOR_PROP ORANGE;
SET COLOR_DOT WHITE;
SET COLOR_ARC YELLOW;
SET COLOR_BODY GREEN;
SET COLOR_NOTE PURPLE;
SET PROP_DISPLAY VALUE;
SET PAGE_NUMBER P120;
FORCEADD QUANTA_TITLE_BLOCK_C..1
(0 0);
FORCEPROP 1 LAST CUSTOM_TXT_CDS <NAME_2>
J 0
(-3175 50);
FORCEPROP 1 LAST CUSTOM_TXT_CDS <NAME_1>
J 0
(-3175 175);
FORCEPROP 1 LAST CUSTOM_TXT_CDS <Q_NUMBER>
J 0
(-1403 103);
DISPLAY 1.212766 (-1403 103);
FORCEPROP 1 LAST CUSTOM_TXT_CDS <Q_PROJ>
J 0
(-2382 102);
DISPLAY 1.212766 (-2382 102);
FORCEPROP 1 LAST CUSTOM_TXT_CDS <Q_REV>
J 0
(-184 103);
DISPLAY 1.212766 (-184 103);
FORCEPROP 1 LAST CUSTOM_TXT_CDS <CON_LAST_MODIFIED>
J 0
(-1885 15);
DISPLAY 0.978723 (-1885 15);
FORCEPROP 1 LAST CUSTOM_TXT_CDS <CON_PAGE_NUM> OF <CON_TOTAL_PAGES>
J 0
(-446 18);
DISPLAY 0.978723 (-446 18);
FORCEPROP 1 LAST Q_TITLE OCP 3.0 - PRESENT
J 0
(-9300 75);
DISPLAY 2.446809 (-9300 75);
PAINT GREEN (-9300 75);
FORCEPROP 1 LAST Q_DEPT BU9
J 1
(-3763 49);
DISPLAY 1.957447 (-3763 49);
PAINT GREEN (-3763 49);
FORCEPROP 2 LAST PAGE_BORDER TRUE
J 0
(-7890 5250);
DISPLAY 0.638298 (-7890 5250);
PAINT PINK (-7890 5250);
DISPLAY INVISIBLE (-7890 5250);
FORCEPROP 2 LAST CDS_LIB pure_quanta
J 0
(0 0);
DISPLAY INVISIBLE (0 0);
FORCEPROP 1 LAST CDS_LMAN_SYM_OUTLINE -9475,6775,100,-125
J 0
(0 0);
DISPLAY 0.468085 (0 0);
PAINT GREEN (0 0);
DISPLAY INVISIBLE (0 0);
FORCEPROP 1 LAST COMMENT_BODY TRUE
J 0
(12 -13);
DISPLAY 0.978723 (12 -13);
PAINT GREEN (12 -13);
DISPLAY INVISIBLE (12 -13);
FORCEPROP 2 LAST CDS_XR_PAGE_TITLE CR-120 : @T6G_MB_LIB.T6G(SCH_1):PAGE120
J 0
(-7890 5250);
DISPLAY 0.638298 (-7890 5250);
PAINT PINK (-7890 5250);
DISPLAY INVISIBLE (-7890 5250);
FORCEPROP 2 LAST CUSTOM_TXT_CDS <XR_PAGE_TITLE>
J 0
(-7890 5250);
DISPLAY 0.638298 (-7890 5250);
PAINT PINK (-7890 5250);
DISPLAY INVISIBLE (-7890 5250);
FORCEPROP 0 LAST CDS_CON_LAST_MODIFIED Wed Mar 09 17:54:29 2022
J 0
(-1885 15);
DISPLAY INVISIBLE (-1885 15);
QUIT
